(kicad_pcb
	(version 20260206)
	(generator "pcbnew")
	(generator_version "10.0")
	(general
		(thickness 1.6)
		(legacy_teardrops no)
	)
	(paper "A4")
	(title_block
		(title "dpb — 14545-sa.0730WZS0815.brd")
		(comment 1 "Honey Badger (Wiwynn) / footprints 910-915 of 1066")
	)
	(layers
		(0 "F.Cu" signal "TOP")
		(4 "In1.Cu" signal "L2GND")
		(6 "In2.Cu" signal "L3")
		(8 "In3.Cu" signal "L4VCC")
		(10 "In4.Cu" signal "L5VCC")
		(12 "In5.Cu" signal "L6")
		(14 "In6.Cu" signal "L7GND")
		(2 "B.Cu" signal "BOTTOM")
		(9 "F.Adhes" user "F.Adhesive")
		(11 "B.Adhes" user "B.Adhesive")
		(13 "F.Paste" user "Package Geometry/Pastemask Top")
		(15 "B.Paste" user "Package Geometry/Pastemask Bottom")
		(5 "F.SilkS" user "Ref Des/Silkscreen Top")
		(7 "B.SilkS" user "Ref Des/Silkscreen Bottom")
		(1 "F.Mask" user "Board Geometry/Soldermask Top")
		(3 "B.Mask" user "Board Geometry/Soldermask Bottom")
		(17 "Dwgs.User" user "User.Drawings")
		(19 "Cmts.User" user "User.Comments")
		(21 "Eco1.User" user "User.Eco1")
		(23 "Eco2.User" user "User.Eco2")
		(25 "Edge.Cuts" user "Board Geometry/Outline")
		(27 "Margin" user)
		(31 "F.CrtYd" user "Package Geometry/Place Bound Top")
		(29 "B.CrtYd" user "Package Geometry/Place Bound Bottom")
		(35 "F.Fab" user "Ref Des/Assembly Top")
		(33 "B.Fab" user "Ref Des/Assembly Bottom")
	)
	(footprint ""
		(layer "F.Cu")
		(at 224.154746 -32.2707 180)
		(property "Reference" "PTC1"
			(at 0 0 180)
			(layer "F.SilkS")
			(hide yes)
			(effects
				(font
					(size 1.27 1.27)
				)
			)
		)
		(property "Value" "ST330U10VDM-2GP"
			(at 0 -9.6012 180)
			(unlocked yes)
			(layer "F.Fab")
			(hide yes)
			(effects
				(font
					(size 1.016 1.016)
					(thickness 0.1524)
				)
			)
		)
		(property "Device Type" "CT7343H150"
			(at 0 -11.1252 180)
			(unlocked yes)
			(layer "F.Fab")
			(hide yes)
			(effects
				(font
					(size 1.016 1.016)
					(thickness 0.1524)
				)
			)
		)
		(duplicate_pad_numbers_are_jumpers no)
		(fp_line
			(start 2.286 4.8768)
			(end -2.286 4.8768)
			(stroke
				(width 0.1524)
				(type default)
			)
			(layer "F.SilkS")
		)
		(fp_line
			(start 2.286 2.032)
			(end 2.286 4.8768)
			(stroke
				(width 0.1524)
				(type default)
			)
			(layer "F.SilkS")
		)
		(fp_line
			(start 2.286 -2.032)
			(end 2.286 -4.8768)
			(stroke
				(width 0.1524)
				(type default)
			)
			(layer "F.SilkS")
		)
		(fp_line
			(start 2.286 -4.8768)
			(end -2.286 -4.8768)
			(stroke
				(width 0.1524)
				(type default)
			)
			(layer "F.SilkS")
		)
		(fp_line
			(start 2.1082 -4.699)
			(end -2.1082 -4.699)
			(stroke
				(width 0.508)
				(type default)
			)
			(layer "F.SilkS")
		)
		(fp_line
			(start -2.286 4.8768)
			(end -2.286 2.032)
			(stroke
				(width 0.1524)
				(type default)
			)
			(layer "F.SilkS")
		)
		(fp_line
			(start -2.286 -4.8768)
			(end -2.286 -2.032)
			(stroke
				(width 0.1524)
				(type default)
			)
			(layer "F.SilkS")
		)
		(fp_rect
			(start -2.1463 3.6449)
			(end 2.1463 -3.6449)
			(stroke
				(width 0)
				(type default)
			)
			(fill no)
			(layer "F.CrtYd")
		)
		(fp_poly
			(pts
				(xy -2.54 4.953) (xy -2.54 4.2926) (xy -3.81 4.2926) (xy -3.81 -4.2926) (xy -2.54 -4.2926) (xy -2.54 -4.953)
				(xy 2.54 -4.953) (xy 2.54 -4.2926) (xy 3.81 -4.2926) (xy 3.81 -1.6256) (xy 2.1463 -1.6256) (xy 2.1463 -3.6449)
				(xy -2.1463 -3.6449) (xy -2.1463 3.6449) (xy 2.1463 3.6449) (xy 2.1463 -1.6129) (xy 3.81 -1.6129)
				(xy 3.81 4.2926) (xy 2.54 4.2926) (xy 2.54 4.953)
			)
			(stroke
				(width 0)
				(type default)
			)
			(fill no)
			(layer "F.CrtYd")
		)
		(fp_rect
			(start 2.54 4.2926)
			(end 3.81 -4.2926)
			(stroke
				(width 0)
				(type default)
			)
			(fill no)
			(layer "F.Fab")
		)
		(fp_rect
			(start -2.54 4.953)
			(end 2.54 -4.953)
			(stroke
				(width 0)
				(type default)
			)
			(fill no)
			(layer "F.Fab")
		)
		(fp_rect
			(start -3.81 4.2926)
			(end -2.54 -4.2926)
			(stroke
				(width 0)
				(type default)
			)
			(fill no)
			(layer "F.Fab")
		)
		(pad "1" smd rect
			(at 0 -3.1496 180)
			(size 2.413 2.286)
			(layers "F.Cu" "F.Mask" "F.Paste")
			(net "P5VA")
		)
		(pad "2" smd rect
			(at 0 3.1496 180)
			(size 2.413 2.286)
			(layers "F.Cu" "F.Mask" "F.Paste")
			(net "GND")
		)
		(zone
			(layer "F.Cu")
			(hatch none 0.5)
			(connect_pads
				(clearance 0)
			)
			(min_thickness 0.25)
			(keepout
				(tracks allowed)
				(vias not_allowed)
				(pads allowed)
				(copperpour not_allowed)
				(footprints allowed)
			)
			(placement
				(enabled no)
				(sheetname "")
			)
			(fill
				(thermal_gap 0.5)
				(thermal_bridge_width 0.5)
				(island_removal_mode 0)
			)
			(polygon
				(pts
					(xy 222.643446 -30.5816) (xy 222.643446 -27.6733) (xy 225.666046 -27.6733) (xy 225.666046 -30.5689)
					(xy 225.666046 -30.8991) (xy 222.643446 -30.8991)
				)
			)
		)
		(zone
			(layer "F.Cu")
			(hatch none 0.5)
			(connect_pads
				(clearance 0)
			)
			(min_thickness 0.25)
			(keepout
				(tracks allowed)
				(vias not_allowed)
				(pads allowed)
				(copperpour not_allowed)
				(footprints allowed)
			)
			(placement
				(enabled no)
				(sheetname "")
			)
			(fill
				(thermal_gap 0.5)
				(thermal_bridge_width 0.5)
				(island_removal_mode 0)
			)
			(polygon
				(pts
					(xy 225.666046 -36.8681) (xy 222.643446 -36.8681) (xy 222.643446 -33.9725) (xy 222.643446 -33.6423)
					(xy 225.666046 -33.6423) (xy 225.666046 -33.9725)
				)
			)
		)
	)
	(footprint ""
		(layer "F.Cu")
		(at 38.353746 -112.296702)
		(property "Reference" "R294"
			(at 0 0 0)
			(layer "F.SilkS")
			(hide yes)
			(effects
				(font
					(size 1.27 1.27)
				)
			)
		)
		(property "Value" "0R2J-2-GP"
			(at 0.064008 -3.993896 0)
			(unlocked yes)
			(layer "F.Fab")
			(hide yes)
			(effects
				(font
					(size 1.016 1.016)
					(thickness 0.1524)
				)
			)
		)
		(property "Device Type" "R402H16"
			(at 0.064008 -5.517896 0)
			(unlocked yes)
			(layer "F.Fab")
			(hide yes)
			(effects
				(font
					(size 1.016 1.016)
					(thickness 0.1524)
				)
			)
		)
		(duplicate_pad_numbers_are_jumpers no)
		(fp_line
			(start -0.508 -0.9398)
			(end -0.508 0.9398)
			(stroke
				(width 0.1524)
				(type default)
			)
			(layer "F.SilkS")
		)
		(fp_line
			(start 0.508 -0.9398)
			(end -0.508 -0.9398)
			(stroke
				(width 0.1524)
				(type default)
			)
			(layer "F.SilkS")
		)
		(fp_rect
			(start -0.508 0.9398)
			(end 0.508 -0.9398)
			(stroke
				(width 0)
				(type default)
			)
			(fill no)
			(layer "F.CrtYd")
		)
		(fp_rect
			(start -0.508 0.9398)
			(end 0.508 -0.9398)
			(stroke
				(width 0)
				(type default)
			)
			(fill no)
			(layer "F.Fab")
		)
		(pad "1" smd custom
			(at 0 -0.4445)
			(size 0.1397 0.1397)
			(layers "F.Cu" "F.Mask" "F.Paste")
			(net "SW_PWR_HDD13")
			(options
				(clearance outline)
				(anchor circle)
			)
			(primitives
				(gr_poly
					(pts
						(arc
							(start -0.1778 -0.2794)
							(mid -0.249642 -0.249642)
							(end -0.2794 -0.1778)
						)
						(arc
							(start -0.2794 0.1778)
							(mid -0.249642 0.249642)
							(end -0.1778 0.2794)
						)
						(arc
							(start 0.1778 0.2794)
							(mid 0.249642 0.249642)
							(end 0.2794 0.1778)
						)
						(arc
							(start 0.2794 -0.1778)
							(mid 0.249642 -0.249642)
							(end 0.1778 -0.2794)
						)
					)
					(width 0)
					(fill yes)
				)
			)
		)
		(pad "2" smd custom
			(at 0 0.4445)
			(size 0.1397 0.1397)
			(layers "F.Cu" "F.Mask" "F.Paste")
			(net "SW_PWR_R_HDD13")
			(options
				(clearance outline)
				(anchor circle)
			)
			(primitives
				(gr_poly
					(pts
						(arc
							(start -0.1778 -0.2794)
							(mid -0.249642 -0.249642)
							(end -0.2794 -0.1778)
						)
						(arc
							(start -0.2794 0.1778)
							(mid -0.249642 0.249642)
							(end -0.1778 0.2794)
						)
						(arc
							(start 0.1778 0.2794)
							(mid 0.249642 0.249642)
							(end 0.2794 0.1778)
						)
						(arc
							(start 0.2794 -0.1778)
							(mid 0.249642 -0.249642)
							(end 0.1778 -0.2794)
						)
					)
					(width 0)
					(fill yes)
				)
			)
		)
	)
	(footprint ""
		(layer "F.Cu")
		(at 180.479446 -457.107036 180)
		(property "Reference" "R485"
			(at 0 0 180)
			(layer "F.SilkS")
			(hide yes)
			(effects
				(font
					(size 1.27 1.27)
				)
			)
		)
		(property "Value" "10KR2F-2-GP"
			(at 0.064008 -3.993896 180)
			(unlocked yes)
			(layer "F.Fab")
			(hide yes)
			(effects
				(font
					(size 1.016 1.016)
					(thickness 0.1524)
				)
			)
		)
		(property "Device Type" "R402H16"
			(at 0.064008 -5.517896 180)
			(unlocked yes)
			(layer "F.Fab")
			(hide yes)
			(effects
				(font
					(size 1.016 1.016)
					(thickness 0.1524)
				)
			)
		)
		(duplicate_pad_numbers_are_jumpers no)
		(fp_line
			(start 0.508 -0.9398)
			(end -0.508 -0.9398)
			(stroke
				(width 0.1524)
				(type default)
			)
			(layer "F.SilkS")
		)
		(fp_line
			(start -0.508 -0.9398)
			(end -0.508 0.9398)
			(stroke
				(width 0.1524)
				(type default)
			)
			(layer "F.SilkS")
		)
		(fp_rect
			(start -0.508 0.9398)
			(end 0.508 -0.9398)
			(stroke
				(width 0)
				(type default)
			)
			(fill no)
			(layer "F.CrtYd")
		)
		(fp_rect
			(start -0.508 0.9398)
			(end 0.508 -0.9398)
			(stroke
				(width 0)
				(type default)
			)
			(fill no)
			(layer "F.Fab")
		)
		(pad "1" smd custom
			(at 0 -0.4445 180)
			(size 0.1397 0.1397)
			(layers "F.Cu" "F.Mask" "F.Paste")
			(net "P5VC")
			(options
				(clearance outline)
				(anchor circle)
			)
			(primitives
				(gr_poly
					(pts
						(arc
							(start -0.1778 -0.2794)
							(mid -0.249642 -0.249642)
							(end -0.2794 -0.1778)
						)
						(arc
							(start -0.2794 0.1778)
							(mid -0.249642 0.249642)
							(end -0.1778 0.2794)
						)
						(arc
							(start 0.1778 0.2794)
							(mid 0.249642 0.249642)
							(end 0.2794 0.1778)
						)
						(arc
							(start 0.2794 -0.1778)
							(mid 0.249642 -0.249642)
							(end 0.1778 -0.2794)
						)
					)
					(width 0)
					(fill yes)
				)
			)
		)
		(pad "2" smd custom
			(at 0 0.4445 180)
			(size 0.1397 0.1397)
			(layers "F.Cu" "F.Mask" "F.Paste")
			(net "P5VC_DIV")
			(options
				(clearance outline)
				(anchor circle)
			)
			(primitives
				(gr_poly
					(pts
						(arc
							(start -0.1778 -0.2794)
							(mid -0.249642 -0.249642)
							(end -0.2794 -0.1778)
						)
						(arc
							(start -0.2794 0.1778)
							(mid -0.249642 0.249642)
							(end -0.1778 0.2794)
						)
						(arc
							(start 0.1778 0.2794)
							(mid 0.249642 0.249642)
							(end 0.2794 0.1778)
						)
						(arc
							(start 0.2794 -0.1778)
							(mid 0.249642 -0.249642)
							(end 0.1778 -0.2794)
						)
					)
					(width 0)
					(fill yes)
				)
			)
		)
	)
	(footprint ""
		(layer "F.Cu")
		(at 81.2546 -500.8626 -90)
		(property "Reference" "R413"
			(at 0 0 270)
			(layer "F.SilkS")
			(hide yes)
			(effects
				(font
					(size 1.27 1.27)
				)
			)
		)
		(property "Value" "0R2J-2-GP"
			(at 0.064008 -3.993896 270)
			(unlocked yes)
			(layer "F.Fab")
			(hide yes)
			(effects
				(font
					(size 1.016 1.016)
					(thickness 0.1524)
				)
			)
		)
		(property "Device Type" "R402H16"
			(at 0.064008 -5.517896 270)
			(unlocked yes)
			(layer "F.Fab")
			(hide yes)
			(effects
				(font
					(size 1.016 1.016)
					(thickness 0.1524)
				)
			)
		)
		(duplicate_pad_numbers_are_jumpers no)
		(fp_line
			(start -0.508 -0.9398)
			(end -0.508 0.9398)
			(stroke
				(width 0.1524)
				(type default)
			)
			(layer "F.SilkS")
		)
		(fp_line
			(start 0.508 -0.9398)
			(end -0.508 -0.9398)
			(stroke
				(width 0.1524)
				(type default)
			)
			(layer "F.SilkS")
		)
		(fp_rect
			(start -0.508 0.9398)
			(end 0.508 -0.9398)
			(stroke
				(width 0)
				(type default)
			)
			(fill no)
			(layer "F.CrtYd")
		)
		(fp_rect
			(start -0.508 0.9398)
			(end 0.508 -0.9398)
			(stroke
				(width 0)
				(type default)
			)
			(fill no)
			(layer "F.Fab")
		)
		(pad "1" smd custom
			(at 0 -0.4445 270)
			(size 0.1397 0.1397)
			(layers "F.Cu" "F.Mask" "F.Paste")
			(net "SW_HDD5_G")
			(options
				(clearance outline)
				(anchor circle)
			)
			(primitives
				(gr_poly
					(pts
						(arc
							(start -0.1778 -0.2794)
							(mid -0.249642 -0.249642)
							(end -0.2794 -0.1778)
						)
						(arc
							(start -0.2794 0.1778)
							(mid -0.249642 0.249642)
							(end -0.1778 0.2794)
						)
						(arc
							(start 0.1778 0.2794)
							(mid 0.249642 0.249642)
							(end 0.2794 0.1778)
						)
						(arc
							(start 0.2794 -0.1778)
							(mid 0.249642 -0.249642)
							(end 0.1778 -0.2794)
						)
					)
					(width 0)
					(fill yes)
				)
			)
		)
		(pad "2" smd custom
			(at 0 0.4445 270)
			(size 0.1397 0.1397)
			(layers "F.Cu" "F.Mask" "F.Paste")
			(net "SW_HDD5_R")
			(options
				(clearance outline)
				(anchor circle)
			)
			(primitives
				(gr_poly
					(pts
						(arc
							(start -0.1778 -0.2794)
							(mid -0.249642 -0.249642)
							(end -0.2794 -0.1778)
						)
						(arc
							(start -0.2794 0.1778)
							(mid -0.249642 0.249642)
							(end -0.1778 0.2794)
						)
						(arc
							(start 0.1778 0.2794)
							(mid 0.249642 0.249642)
							(end 0.2794 0.1778)
						)
						(arc
							(start 0.2794 -0.1778)
							(mid 0.249642 -0.249642)
							(end 0.1778 -0.2794)
						)
					)
					(width 0)
					(fill yes)
				)
			)
		)
	)
	(footprint ""
		(layer "F.Cu")
		(at 165.112446 -456.218036 90)
		(property "Reference" "R380"
			(at 0 0 90)
			(layer "F.SilkS")
			(hide yes)
			(effects
				(font
					(size 1.27 1.27)
				)
			)
		)
		(property "Value" "0R2J-2-GP"
			(at 0.064008 -3.993896 90)
			(unlocked yes)
			(layer "F.Fab")
			(hide yes)
			(effects
				(font
					(size 1.016 1.016)
					(thickness 0.1524)
				)
			)
		)
		(property "Device Type" "R402H16"
			(at 0.064008 -5.517896 90)
			(unlocked yes)
			(layer "F.Fab")
			(hide yes)
			(effects
				(font
					(size 1.016 1.016)
					(thickness 0.1524)
				)
			)
		)
		(duplicate_pad_numbers_are_jumpers no)
		(fp_line
			(start 0.508 -0.9398)
			(end -0.508 -0.9398)
			(stroke
				(width 0.1524)
				(type default)
			)
			(layer "F.SilkS")
		)
		(fp_line
			(start -0.508 -0.9398)
			(end -0.508 0.9398)
			(stroke
				(width 0.1524)
				(type default)
			)
			(layer "F.SilkS")
		)
		(fp_rect
			(start -0.508 0.9398)
			(end 0.508 -0.9398)
			(stroke
				(width 0)
				(type default)
			)
			(fill no)
			(layer "F.CrtYd")
		)
		(fp_rect
			(start -0.508 0.9398)
			(end 0.508 -0.9398)
			(stroke
				(width 0)
				(type default)
			)
			(fill no)
			(layer "F.Fab")
		)
		(pad "1" smd custom
			(at 0 -0.4445 90)
			(size 0.1397 0.1397)
			(layers "F.Cu" "F.Mask" "F.Paste")
			(net "P5VB_DIV")
			(options
				(clearance outline)
				(anchor circle)
			)
			(primitives
				(gr_poly
					(pts
						(arc
							(start -0.1778 -0.2794)
							(mid -0.249642 -0.249642)
							(end -0.2794 -0.1778)
						)
						(arc
							(start -0.2794 0.1778)
							(mid -0.249642 0.249642)
							(end -0.1778 0.2794)
						)
						(arc
							(start 0.1778 0.2794)
							(mid 0.249642 0.249642)
							(end 0.2794 0.1778)
						)
						(arc
							(start 0.2794 -0.1778)
							(mid 0.249642 -0.249642)
							(end 0.1778 -0.2794)
						)
					)
					(width 0)
					(fill yes)
				)
			)
		)
		(pad "2" smd custom
			(at 0 0.4445 90)
			(size 0.1397 0.1397)
			(layers "F.Cu" "F.Mask" "F.Paste")
			(net "P5VB_SENSE")
			(options
				(clearance outline)
				(anchor circle)
			)
			(primitives
				(gr_poly
					(pts
						(arc
							(start -0.1778 -0.2794)
							(mid -0.249642 -0.249642)
							(end -0.2794 -0.1778)
						)
						(arc
							(start -0.2794 0.1778)
							(mid -0.249642 0.249642)
							(end -0.1778 0.2794)
						)
						(arc
							(start 0.1778 0.2794)
							(mid 0.249642 0.249642)
							(end 0.2794 0.1778)
						)
						(arc
							(start 0.2794 -0.1778)
							(mid 0.249642 -0.249642)
							(end 0.1778 -0.2794)
						)
					)
					(width 0)
					(fill yes)
				)
			)
		)
	)
	(footprint ""
		(layer "F.Cu")
		(at 58.927746 -24.6507 90)
		(property "Reference" "PR30"
			(at 0 0 90)
			(layer "F.SilkS")
			(hide yes)
			(effects
				(font
					(size 1.27 1.27)
				)
			)
		)
		(property "Value" "115KR2F-GP"
			(at 0.064008 -3.993896 90)
			(unlocked yes)
			(layer "F.Fab")
			(hide yes)
			(effects
				(font
					(size 1.016 1.016)
					(thickness 0.1524)
				)
			)
		)
		(property "Device Type" "R402H16"
			(at 0.064008 -5.517896 90)
			(unlocked yes)
			(layer "F.Fab")
			(hide yes)
			(effects
				(font
					(size 1.016 1.016)
					(thickness 0.1524)
				)
			)
		)
		(duplicate_pad_numbers_are_jumpers no)
		(fp_line
			(start 0.508 -0.9398)
			(end -0.508 -0.9398)
			(stroke
				(width 0.1524)
				(type default)
			)
			(layer "F.SilkS")
		)
		(fp_line
			(start -0.508 -0.9398)
			(end -0.508 0.9398)
			(stroke
				(width 0.1524)
				(type default)
			)
			(layer "F.SilkS")
		)
		(fp_rect
			(start -0.508 0.9398)
			(end 0.508 -0.9398)
			(stroke
				(width 0)
				(type default)
			)
			(fill no)
			(layer "F.CrtYd")
		)
		(fp_rect
			(start -0.508 0.9398)
			(end 0.508 -0.9398)
			(stroke
				(width 0)
				(type default)
			)
			(fill no)
			(layer "F.Fab")
		)
		(pad "1" smd custom
			(at 0 -0.4445 90)
			(size 0.1397 0.1397)
			(layers "F.Cu" "F.Mask" "F.Paste")
			(net "P5VB_TRIP")
			(options
				(clearance outline)
				(anchor circle)
			)
			(primitives
				(gr_poly
					(pts
						(arc
							(start -0.1778 -0.2794)
							(mid -0.249642 -0.249642)
							(end -0.2794 -0.1778)
						)
						(arc
							(start -0.2794 0.1778)
							(mid -0.249642 0.249642)
							(end -0.1778 0.2794)
						)
						(arc
							(start 0.1778 0.2794)
							(mid 0.249642 0.249642)
							(end 0.2794 0.1778)
						)
						(arc
							(start 0.2794 -0.1778)
							(mid 0.249642 -0.249642)
							(end 0.1778 -0.2794)
						)
					)
					(width 0)
					(fill yes)
				)
			)
		)
		(pad "2" smd custom
			(at 0 0.4445 90)
			(size 0.1397 0.1397)
			(layers "F.Cu" "F.Mask" "F.Paste")
			(net "P5VB_AGND")
			(options
				(clearance outline)
				(anchor circle)
			)
			(primitives
				(gr_poly
					(pts
						(arc
							(start -0.1778 -0.2794)
							(mid -0.249642 -0.249642)
							(end -0.2794 -0.1778)
						)
						(arc
							(start -0.2794 0.1778)
							(mid -0.249642 0.249642)
							(end -0.1778 0.2794)
						)
						(arc
							(start 0.1778 0.2794)
							(mid 0.249642 0.249642)
							(end 0.2794 0.1778)
						)
						(arc
							(start 0.2794 -0.1778)
							(mid 0.249642 -0.249642)
							(end 0.1778 -0.2794)
						)
					)
					(width 0)
					(fill yes)
				)
			)
		)
	)
)
